# T6G (Grand Teton) — schematic netlist excerpt (pin names and nets, part order shuffled) for the footprints in the layout excerpt that follows; sources: Cadence DE-HDL packaged netlist, KiCad conversion of 04192023_DAF0TMB3IC0_F0TG_MB_C_brd_V02_OCP.brd

R3107  Q_RES  0 5% CHIP  pkg 0402LF  page 248 : A = SMB_2_BMC_GPU_SCL ; B = SMB_2_BMC_GPU_R_SCL
R6501  Q_RES  100K 1% CHIP  pkg 0402LF  page 188 : A = PWRGD_P3V3_EN_R ; B = GND

(kicad_pcb
	(version 20260206)
	(generator "pcbnew")
	(generator_version "10.0")
	(general
		(thickness 1.6)
		(legacy_teardrops no)
	)
	(paper "A4")
	(title_block
		(title "04192023_DAF0TMB3IC0_F0TG_MB_C_brd_V02_OCP.brd")
		(comment 1 "Grand Teton / footprints 741-742 of 8354")
	)
	(layers
		(0 "F.Cu" signal "TOP")
		(4 "In1.Cu" signal "GND")
		(6 "In2.Cu" signal "IN1")
		(8 "In3.Cu" signal "GND1")
		(10 "In4.Cu" signal "IN2")
		(12 "In5.Cu" signal "GND2")
		(14 "In6.Cu" signal "IN3")
		(16 "In7.Cu" signal "GND3")
		(18 "In8.Cu" signal "VCC")
		(20 "In9.Cu" signal "VCC1")
		(22 "In10.Cu" signal "GND4")
		(24 "In11.Cu" signal "IN4")
		(26 "In12.Cu" signal "GND5")
		(28 "In13.Cu" signal "IN5")
		(30 "In14.Cu" signal "GND6")
		(32 "In15.Cu" signal "IN6")
		(34 "In16.Cu" signal "GND7")
		(2 "B.Cu" signal "BOTTOM")
		(9 "F.Adhes" user "F.Adhesive")
		(11 "B.Adhes" user "B.Adhesive")
		(13 "F.Paste" user "Package Geometry/Pastemask Top")
		(15 "B.Paste" user "Package Geometry/Pastemask Bottom")
		(5 "F.SilkS" user "Ref Des/Silkscreen Top")
		(7 "B.SilkS" user "Ref Des/Silkscreen Bottom")
		(1 "F.Mask" user "Board Geometry/Soldermask Top")
		(3 "B.Mask" user "Board Geometry/Soldermask Bottom")
		(17 "Dwgs.User" user "User.Drawings")
		(19 "Cmts.User" user "User.Comments")
		(21 "Eco1.User" user "User.Eco1")
		(23 "Eco2.User" user "User.Eco2")
		(25 "Edge.Cuts" user "Board Geometry/Outline")
		(27 "Margin" user)
		(31 "F.CrtYd" user "Package Geometry/Place Bound Top")
		(29 "B.CrtYd" user "Package Geometry/Place Bound Bottom")
		(35 "F.Fab" user "Ref Des/Assembly Top")
		(33 "B.Fab" user "Ref Des/Assembly Bottom")
	)
	(footprint ""
		(layer "F.Cu")
		(at 35.881818 -438.465214 180)
		(property "Reference" "R3107"
			(at 0 0 180)
			(layer "F.SilkS")
			(hide yes)
			(effects
				(font
					(size 1.27 1.27)
				)
			)
		)
		(property "Value" ""
			(at 0 0 180)
			(layer "F.Fab")
			(effects
				(font
					(size 1.27 1.27)
				)
			)
		)
		(duplicate_pad_numbers_are_jumpers no)
		(fp_line
			(start 0.7874 0.4064)
			(end -0.7874 0.4064)
			(stroke
				(width 0.1524)
				(type default)
			)
			(layer "F.SilkS")
		)
		(fp_line
			(start 0.7874 -0.4064)
			(end 0.7874 0.4064)
			(stroke
				(width 0.1524)
				(type default)
			)
			(layer "F.SilkS")
		)
		(fp_line
			(start -0.7874 0.4064)
			(end -0.7874 -0.4064)
			(stroke
				(width 0.1524)
				(type default)
			)
			(layer "F.SilkS")
		)
		(fp_line
			(start -0.7874 -0.4064)
			(end 0.7874 -0.4064)
			(stroke
				(width 0.1524)
				(type default)
			)
			(layer "F.SilkS")
		)
		(fp_line
			(start 0.67945 0.3048)
			(end 0.120396 0.3048)
			(stroke
				(width 0.1)
				(type default)
			)
			(layer "F.Fab")
		)
		(fp_line
			(start 0.67945 -0.3048)
			(end 0.67945 0.3048)
			(stroke
				(width 0.1)
				(type default)
			)
			(layer "F.Fab")
		)
		(fp_line
			(start 0.12065 -0.2794)
			(end 0.12065 -0.3048)
			(stroke
				(width 0.1)
				(type default)
			)
			(layer "F.Fab")
		)
		(fp_line
			(start 0.12065 -0.3048)
			(end 0.67945 -0.3048)
			(stroke
				(width 0.1)
				(type default)
			)
			(layer "F.Fab")
		)
		(fp_line
			(start 0.120396 0.3048)
			(end 0.120396 0.2794)
			(stroke
				(width 0.1)
				(type default)
			)
			(layer "F.Fab")
		)
		(fp_line
			(start 0.120396 0.2794)
			(end -0.12065 0.2794)
			(stroke
				(width 0.1)
				(type default)
			)
			(layer "F.Fab")
		)
		(fp_line
			(start -0.12065 0.3048)
			(end -0.67945 0.3048)
			(stroke
				(width 0.1)
				(type default)
			)
			(layer "F.Fab")
		)
		(fp_line
			(start -0.12065 0.2794)
			(end -0.12065 0.3048)
			(stroke
				(width 0.1)
				(type default)
			)
			(layer "F.Fab")
		)
		(fp_line
			(start -0.12065 -0.2794)
			(end 0.12065 -0.2794)
			(stroke
				(width 0.1)
				(type default)
			)
			(layer "F.Fab")
		)
		(fp_line
			(start -0.12065 -0.305054)
			(end -0.12065 -0.2794)
			(stroke
				(width 0.1)
				(type default)
			)
			(layer "F.Fab")
		)
		(fp_line
			(start -0.67945 0.3048)
			(end -0.67945 -0.305054)
			(stroke
				(width 0.1)
				(type default)
			)
			(layer "F.Fab")
		)
		(fp_line
			(start -0.67945 -0.305054)
			(end -0.12065 -0.305054)
			(stroke
				(width 0.1)
				(type default)
			)
			(layer "F.Fab")
		)
		(pad "1" smd circle
			(at -0.40005 0 180)
			(size 0 0)
			(layers "F.Cu" "F.Mask" "F.Paste")
			(net "SMB_2_BMC_GPU_SCL")
		)
		(pad "2" smd circle
			(at 0.40005 0 180)
			(size 0 0)
			(layers "F.Cu" "F.Mask" "F.Paste")
			(net "SMB_2_BMC_GPU_R_SCL")
		)
	)
	(footprint ""
		(layer "F.Cu")
		(at 111.633 -123.952 -90)
		(property "Reference" "R6501"
			(at 0 0 270)
			(layer "F.SilkS")
			(hide yes)
			(effects
				(font
					(size 1.27 1.27)
				)
			)
		)
		(property "Value" ""
			(at 0 0 270)
			(layer "F.Fab")
			(effects
				(font
					(size 1.27 1.27)
				)
			)
		)
		(duplicate_pad_numbers_are_jumpers no)
		(fp_line
			(start -0.7874 0.4064)
			(end -0.7874 -0.4064)
			(stroke
				(width 0.1524)
				(type default)
			)
			(layer "F.SilkS")
		)
		(fp_line
			(start 0.7874 0.4064)
			(end -0.7874 0.4064)
			(stroke
				(width 0.1524)
				(type default)
			)
			(layer "F.SilkS")
		)
		(fp_line
			(start -0.7874 -0.4064)
			(end 0.7874 -0.4064)
			(stroke
				(width 0.1524)
				(type default)
			)
			(layer "F.SilkS")
		)
		(fp_line
			(start 0.7874 -0.4064)
			(end 0.7874 0.4064)
			(stroke
				(width 0.1524)
				(type default)
			)
			(layer "F.SilkS")
		)
		(fp_line
			(start -0.67945 0.3048)
			(end -0.67945 -0.305054)
			(stroke
				(width 0.1)
				(type default)
			)
			(layer "F.Fab")
		)
		(fp_line
			(start -0.12065 0.3048)
			(end -0.67945 0.3048)
			(stroke
				(width 0.1)
				(type default)
			)
			(layer "F.Fab")
		)
		(fp_line
			(start 0.120396 0.3048)
			(end 0.120396 0.2794)
			(stroke
				(width 0.1)
				(type default)
			)
			(layer "F.Fab")
		)
		(fp_line
			(start 0.67945 0.3048)
			(end 0.120396 0.3048)
			(stroke
				(width 0.1)
				(type default)
			)
			(layer "F.Fab")
		)
		(fp_line
			(start -0.12065 0.2794)
			(end -0.12065 0.3048)
			(stroke
				(width 0.1)
				(type default)
			)
			(layer "F.Fab")
		)
		(fp_line
			(start 0.120396 0.2794)
			(end -0.12065 0.2794)
			(stroke
				(width 0.1)
				(type default)
			)
			(layer "F.Fab")
		)
		(fp_line
			(start -0.12065 -0.2794)
			(end 0.12065 -0.2794)
			(stroke
				(width 0.1)
				(type default)
			)
			(layer "F.Fab")
		)
		(fp_line
			(start 0.12065 -0.2794)
			(end 0.12065 -0.3048)
			(stroke
				(width 0.1)
				(type default)
			)
			(layer "F.Fab")
		)
		(fp_line
			(start 0.12065 -0.3048)
			(end 0.67945 -0.3048)
			(stroke
				(width 0.1)
				(type default)
			)
			(layer "F.Fab")
		)
		(fp_line
			(start 0.67945 -0.3048)
			(end 0.67945 0.3048)
			(stroke
				(width 0.1)
				(type default)
			)
			(layer "F.Fab")
		)
		(fp_line
			(start -0.67945 -0.305054)
			(end -0.12065 -0.305054)
			(stroke
				(width 0.1)
				(type default)
			)
			(layer "F.Fab")
		)
		(fp_line
			(start -0.12065 -0.305054)
			(end -0.12065 -0.2794)
			(stroke
				(width 0.1)
				(type default)
			)
			(layer "F.Fab")
		)
		(pad "1" smd circle
			(at -0.40005 0 270)
			(size 0 0)
			(layers "F.Cu" "F.Mask" "F.Paste")
			(net "PWRGD_P3V3_EN_R")
		)
		(pad "2" smd circle
			(at 0.40005 0 270)
			(size 0 0)
			(layers "F.Cu" "F.Mask" "F.Paste")
			(net "GND")
		)
	)
)
